# S9S_MB_2U (Grand Teton) — schematic netlist excerpt (pin names and nets, part order shuffled) for the footprints in the layout excerpt that follows; sources: Cadence DE-HDL packaged netlist, KiCad conversion of 03242023_DA0F0TMBIJ0_F0T_Motherboard_J_brd_V01_OCP.brd

R2842  Q_RES  4.7K 5% CHIP  pkg 0402LF  page 148 : A = P3V3_AUX ; B = FM_GPU_PWRGD_N
C1612  Q_CAP  1UF 25V 10% X6S  pkg C0402  page 197 : A = P3V3_AUX ; B = GND

(kicad_pcb
	(version 20260206)
	(generator "pcbnew")
	(generator_version "10.0")
	(general
		(thickness 1.6)
		(legacy_teardrops no)
	)
	(paper "A4")
	(title_block
		(title "03242023_DA0F0TMBIJ0_F0T_Motherboard_J_brd_V01_OCP.brd")
		(comment 1 "Grand Teton / footprints 4022-4023 of 6105")
	)
	(layers
		(0 "F.Cu" signal "TOP")
		(4 "In1.Cu" signal "GND")
		(6 "In2.Cu" signal "IN1")
		(8 "In3.Cu" signal "GND1")
		(10 "In4.Cu" signal "IN2")
		(12 "In5.Cu" signal "GND2")
		(14 "In6.Cu" signal "IN3")
		(16 "In7.Cu" signal "GND3")
		(18 "In8.Cu" signal "VCC")
		(20 "In9.Cu" signal "VCC1")
		(22 "In10.Cu" signal "GND4")
		(24 "In11.Cu" signal "IN4")
		(26 "In12.Cu" signal "GND5")
		(28 "In13.Cu" signal "IN5")
		(30 "In14.Cu" signal "GND6")
		(32 "In15.Cu" signal "IN6")
		(34 "In16.Cu" signal "GND7")
		(2 "B.Cu" signal "BOTTOM")
		(9 "F.Adhes" user "F.Adhesive")
		(11 "B.Adhes" user "B.Adhesive")
		(13 "F.Paste" user "Package Geometry/Pastemask Top")
		(15 "B.Paste" user "Package Geometry/Pastemask Bottom")
		(5 "F.SilkS" user "Ref Des/Silkscreen Top")
		(7 "B.SilkS" user "Ref Des/Silkscreen Bottom")
		(1 "F.Mask" user "Board Geometry/Soldermask Top")
		(3 "B.Mask" user "Board Geometry/Soldermask Bottom")
		(17 "Dwgs.User" user "User.Drawings")
		(19 "Cmts.User" user "User.Comments")
		(21 "Eco1.User" user "User.Eco1")
		(23 "Eco2.User" user "User.Eco2")
		(25 "Edge.Cuts" user "Board Geometry/Outline")
		(27 "Margin" user)
		(31 "F.CrtYd" user "Package Geometry/Place Bound Top")
		(29 "B.CrtYd" user "Package Geometry/Place Bound Bottom")
		(35 "F.Fab" user "Ref Des/Assembly Top")
		(33 "B.Fab" user "Ref Des/Assembly Bottom")
	)
	(footprint ""
		(layer "F.Cu")
		(at 307.3146 -62.375542 90)
		(property "Reference" "C1612"
			(at 0 0 90)
			(layer "F.SilkS")
			(hide yes)
			(effects
				(font
					(size 1.27 1.27)
				)
			)
		)
		(property "Value" ""
			(at 0 0 90)
			(layer "F.Fab")
			(effects
				(font
					(size 1.27 1.27)
				)
			)
		)
		(duplicate_pad_numbers_are_jumpers no)
		(fp_line
			(start 0.7874 -0.4064)
			(end 0.7874 0.4064)
			(stroke
				(width 0.1524)
				(type default)
			)
			(layer "F.SilkS")
		)
		(fp_line
			(start -0.7874 -0.4064)
			(end 0.7874 -0.4064)
			(stroke
				(width 0.1524)
				(type default)
			)
			(layer "F.SilkS")
		)
		(fp_line
			(start 0.7874 0.4064)
			(end -0.7874 0.4064)
			(stroke
				(width 0.1524)
				(type default)
			)
			(layer "F.SilkS")
		)
		(fp_line
			(start -0.7874 0.4064)
			(end -0.7874 -0.4064)
			(stroke
				(width 0.1524)
				(type default)
			)
			(layer "F.SilkS")
		)
		(fp_line
			(start -0.12065 -0.305054)
			(end -0.12065 -0.2794)
			(stroke
				(width 0.1)
				(type default)
			)
			(layer "F.Fab")
		)
		(fp_line
			(start -0.67945 -0.305054)
			(end -0.12065 -0.305054)
			(stroke
				(width 0.1)
				(type default)
			)
			(layer "F.Fab")
		)
		(fp_line
			(start 0.67945 -0.3048)
			(end 0.67945 0.3048)
			(stroke
				(width 0.1)
				(type default)
			)
			(layer "F.Fab")
		)
		(fp_line
			(start 0.12065 -0.3048)
			(end 0.67945 -0.3048)
			(stroke
				(width 0.1)
				(type default)
			)
			(layer "F.Fab")
		)
		(fp_line
			(start 0.12065 -0.2794)
			(end 0.12065 -0.3048)
			(stroke
				(width 0.1)
				(type default)
			)
			(layer "F.Fab")
		)
		(fp_line
			(start -0.12065 -0.2794)
			(end 0.12065 -0.2794)
			(stroke
				(width 0.1)
				(type default)
			)
			(layer "F.Fab")
		)
		(fp_line
			(start 0.120396 0.2794)
			(end -0.12065 0.2794)
			(stroke
				(width 0.1)
				(type default)
			)
			(layer "F.Fab")
		)
		(fp_line
			(start -0.12065 0.2794)
			(end -0.12065 0.3048)
			(stroke
				(width 0.1)
				(type default)
			)
			(layer "F.Fab")
		)
		(fp_line
			(start 0.67945 0.3048)
			(end 0.120396 0.3048)
			(stroke
				(width 0.1)
				(type default)
			)
			(layer "F.Fab")
		)
		(fp_line
			(start 0.120396 0.3048)
			(end 0.120396 0.2794)
			(stroke
				(width 0.1)
				(type default)
			)
			(layer "F.Fab")
		)
		(fp_line
			(start -0.12065 0.3048)
			(end -0.67945 0.3048)
			(stroke
				(width 0.1)
				(type default)
			)
			(layer "F.Fab")
		)
		(fp_line
			(start -0.67945 0.3048)
			(end -0.67945 -0.305054)
			(stroke
				(width 0.1)
				(type default)
			)
			(layer "F.Fab")
		)
		(pad "1" smd circle
			(at -0.40005 0 90)
			(size 0 0)
			(layers "F.Cu" "F.Mask" "F.Paste")
			(net "P3V3_AUX")
		)
		(pad "2" smd circle
			(at 0.40005 0 90)
			(size 0 0)
			(layers "F.Cu" "F.Mask" "F.Paste")
			(net "GND")
		)
	)
	(footprint ""
		(layer "F.Cu")
		(at 31.891732 -416.016948 180)
		(property "Reference" "R2842"
			(at 0 0 180)
			(layer "F.SilkS")
			(hide yes)
			(effects
				(font
					(size 1.27 1.27)
				)
			)
		)
		(property "Value" ""
			(at 0 0 180)
			(layer "F.Fab")
			(effects
				(font
					(size 1.27 1.27)
				)
			)
		)
		(duplicate_pad_numbers_are_jumpers no)
		(fp_line
			(start 0.7874 0.4064)
			(end -0.7874 0.4064)
			(stroke
				(width 0.1524)
				(type default)
			)
			(layer "F.SilkS")
		)
		(fp_line
			(start 0.7874 -0.4064)
			(end 0.7874 0.4064)
			(stroke
				(width 0.1524)
				(type default)
			)
			(layer "F.SilkS")
		)
		(fp_line
			(start -0.7874 0.4064)
			(end -0.7874 -0.4064)
			(stroke
				(width 0.1524)
				(type default)
			)
			(layer "F.SilkS")
		)
		(fp_line
			(start -0.7874 -0.4064)
			(end 0.7874 -0.4064)
			(stroke
				(width 0.1524)
				(type default)
			)
			(layer "F.SilkS")
		)
		(fp_line
			(start 0.67945 0.3048)
			(end 0.120396 0.3048)
			(stroke
				(width 0.1)
				(type default)
			)
			(layer "F.Fab")
		)
		(fp_line
			(start 0.67945 -0.3048)
			(end 0.67945 0.3048)
			(stroke
				(width 0.1)
				(type default)
			)
			(layer "F.Fab")
		)
		(fp_line
			(start 0.12065 -0.2794)
			(end 0.12065 -0.3048)
			(stroke
				(width 0.1)
				(type default)
			)
			(layer "F.Fab")
		)
		(fp_line
			(start 0.12065 -0.3048)
			(end 0.67945 -0.3048)
			(stroke
				(width 0.1)
				(type default)
			)
			(layer "F.Fab")
		)
		(fp_line
			(start 0.120396 0.3048)
			(end 0.120396 0.2794)
			(stroke
				(width 0.1)
				(type default)
			)
			(layer "F.Fab")
		)
		(fp_line
			(start 0.120396 0.2794)
			(end -0.12065 0.2794)
			(stroke
				(width 0.1)
				(type default)
			)
			(layer "F.Fab")
		)
		(fp_line
			(start -0.12065 0.3048)
			(end -0.67945 0.3048)
			(stroke
				(width 0.1)
				(type default)
			)
			(layer "F.Fab")
		)
		(fp_line
			(start -0.12065 0.2794)
			(end -0.12065 0.3048)
			(stroke
				(width 0.1)
				(type default)
			)
			(layer "F.Fab")
		)
		(fp_line
			(start -0.12065 -0.2794)
			(end 0.12065 -0.2794)
			(stroke
				(width 0.1)
				(type default)
			)
			(layer "F.Fab")
		)
		(fp_line
			(start -0.12065 -0.305054)
			(end -0.12065 -0.2794)
			(stroke
				(width 0.1)
				(type default)
			)
			(layer "F.Fab")
		)
		(fp_line
			(start -0.67945 0.3048)
			(end -0.67945 -0.305054)
			(stroke
				(width 0.1)
				(type default)
			)
			(layer "F.Fab")
		)
		(fp_line
			(start -0.67945 -0.305054)
			(end -0.12065 -0.305054)
			(stroke
				(width 0.1)
				(type default)
			)
			(layer "F.Fab")
		)
		(pad "1" smd circle
			(at -0.40005 0 180)
			(size 0 0)
			(layers "F.Cu" "F.Mask" "F.Paste")
			(net "P3V3_AUX")
		)
		(pad "2" smd circle
			(at 0.40005 0 180)
			(size 0 0)
			(layers "F.Cu" "F.Mask" "F.Paste")
			(net "FM_GPU_PWRGD_N")
		)
	)
)
